(kicad_pcb
	(version 20260206)
	(generator "pcbnew")
	(generator_version "10.0")
	(general
		(thickness 1.6)
		(legacy_teardrops no)
	)
	(paper "A4")
	(title_block
		(title "dpb — 14545-sa.0730WZS0815.brd")
		(comment 1 "Honey Badger (Wiwynn) / footprints 245-248 of 1066")
	)
	(layers
		(0 "F.Cu" signal "TOP")
		(4 "In1.Cu" signal "L2GND")
		(6 "In2.Cu" signal "L3")
		(8 "In3.Cu" signal "L4VCC")
		(10 "In4.Cu" signal "L5VCC")
		(12 "In5.Cu" signal "L6")
		(14 "In6.Cu" signal "L7GND")
		(2 "B.Cu" signal "BOTTOM")
		(9 "F.Adhes" user "F.Adhesive")
		(11 "B.Adhes" user "B.Adhesive")
		(13 "F.Paste" user "Package Geometry/Pastemask Top")
		(15 "B.Paste" user "Package Geometry/Pastemask Bottom")
		(5 "F.SilkS" user "Ref Des/Silkscreen Top")
		(7 "B.SilkS" user "Ref Des/Silkscreen Bottom")
		(1 "F.Mask" user "Board Geometry/Soldermask Top")
		(3 "B.Mask" user "Board Geometry/Soldermask Bottom")
		(17 "Dwgs.User" user "User.Drawings")
		(19 "Cmts.User" user "User.Comments")
		(21 "Eco1.User" user "User.Eco1")
		(23 "Eco2.User" user "User.Eco2")
		(25 "Edge.Cuts" user "Board Geometry/Outline")
		(27 "Margin" user)
		(31 "F.CrtYd" user "Package Geometry/Place Bound Top")
		(29 "B.CrtYd" user "Package Geometry/Place Bound Bottom")
		(35 "F.Fab" user "Ref Des/Assembly Top")
		(33 "B.Fab" user "Ref Des/Assembly Bottom")
	)
	(footprint ""
		(layer "F.Cu")
		(at 46.354746 -18.5547 180)
		(property "Reference" "PC20"
			(at 0 0 180)
			(layer "F.SilkS")
			(hide yes)
			(effects
				(font
					(size 1.27 1.27)
				)
			)
		)
		(property "Value" "SC2200P50V2KX-2GP"
			(at 1.1811 -2.7051 180)
			(unlocked yes)
			(layer "F.Fab")
			(hide yes)
			(effects
				(font
					(size 1.016 1.016)
					(thickness 0.1524)
				)
			)
		)
		(property "Device Type" "C402H22"
			(at 1.1811 -4.2291 180)
			(unlocked yes)
			(layer "F.Fab")
			(hide yes)
			(effects
				(font
					(size 1.016 1.016)
					(thickness 0.1524)
				)
			)
		)
		(duplicate_pad_numbers_are_jumpers no)
		(fp_rect
			(start -0.4318 0.9525)
			(end 0.4318 -0.9525)
			(stroke
				(width 0)
				(type default)
			)
			(fill no)
			(layer "F.CrtYd")
		)
		(fp_rect
			(start -0.4318 0.9525)
			(end 0.4318 -0.9525)
			(stroke
				(width 0)
				(type default)
			)
			(fill no)
			(layer "F.Fab")
		)
		(pad "1" smd custom
			(at 0 -0.4445 180)
			(size 0.1524 0.1524)
			(layers "F.Cu" "F.Mask" "F.Paste")
			(net "P5VB_LL")
			(options
				(clearance outline)
				(anchor circle)
			)
			(primitives
				(gr_poly
					(pts
						(arc
							(start 0.3048 -0.2032)
							(mid 0.275042 -0.275042)
							(end 0.2032 -0.3048)
						)
						(arc
							(start -0.2032 -0.3048)
							(mid -0.275042 -0.275042)
							(end -0.3048 -0.2032)
						)
						(arc
							(start -0.3048 0.2032)
							(mid -0.275042 0.275042)
							(end -0.2032 0.3048)
						)
						(arc
							(start 0.2032 0.3048)
							(mid 0.275042 0.275042)
							(end 0.3048 0.2032)
						)
					)
					(width 0)
					(fill yes)
				)
			)
		)
		(pad "2" smd custom
			(at 0 0.4445 180)
			(size 0.1524 0.1524)
			(layers "F.Cu" "F.Mask" "F.Paste")
			(net "P5VB_SNB")
			(options
				(clearance outline)
				(anchor circle)
			)
			(primitives
				(gr_poly
					(pts
						(arc
							(start 0.3048 -0.2032)
							(mid 0.275042 -0.275042)
							(end 0.2032 -0.3048)
						)
						(arc
							(start -0.2032 -0.3048)
							(mid -0.275042 -0.275042)
							(end -0.3048 -0.2032)
						)
						(arc
							(start -0.3048 0.2032)
							(mid -0.275042 0.275042)
							(end -0.2032 0.3048)
						)
						(arc
							(start 0.2032 0.3048)
							(mid 0.275042 0.275042)
							(end 0.3048 0.2032)
						)
					)
					(width 0)
					(fill yes)
				)
			)
		)
	)
	(footprint ""
		(layer "F.Cu")
		(at 197.911974 -388.084822 -90)
		(property "Reference" "R428"
			(at 0 0 270)
			(layer "F.SilkS")
			(hide yes)
			(effects
				(font
					(size 1.27 1.27)
				)
			)
		)
		(property "Value" "4K7R2J-2-GP"
			(at 0.064008 -3.993896 270)
			(unlocked yes)
			(layer "F.Fab")
			(hide yes)
			(effects
				(font
					(size 1.016 1.016)
					(thickness 0.1524)
				)
			)
		)
		(property "Device Type" "R402H16"
			(at 0.064008 -5.517896 270)
			(unlocked yes)
			(layer "F.Fab")
			(hide yes)
			(effects
				(font
					(size 1.016 1.016)
					(thickness 0.1524)
				)
			)
		)
		(duplicate_pad_numbers_are_jumpers no)
		(fp_line
			(start -0.508 -0.9398)
			(end -0.508 0.9398)
			(stroke
				(width 0.1524)
				(type default)
			)
			(layer "F.SilkS")
		)
		(fp_line
			(start 0.508 -0.9398)
			(end -0.508 -0.9398)
			(stroke
				(width 0.1524)
				(type default)
			)
			(layer "F.SilkS")
		)
		(fp_rect
			(start -0.508 0.9398)
			(end 0.508 -0.9398)
			(stroke
				(width 0)
				(type default)
			)
			(fill no)
			(layer "F.CrtYd")
		)
		(fp_rect
			(start -0.508 0.9398)
			(end 0.508 -0.9398)
			(stroke
				(width 0)
				(type default)
			)
			(fill no)
			(layer "F.Fab")
		)
		(pad "1" smd custom
			(at 0 -0.4445 270)
			(size 0.1397 0.1397)
			(layers "F.Cu" "F.Mask" "F.Paste")
			(net "P3V3")
			(options
				(clearance outline)
				(anchor circle)
			)
			(primitives
				(gr_poly
					(pts
						(arc
							(start -0.1778 -0.2794)
							(mid -0.249642 -0.249642)
							(end -0.2794 -0.1778)
						)
						(arc
							(start -0.2794 0.1778)
							(mid -0.249642 0.249642)
							(end -0.1778 0.2794)
						)
						(arc
							(start 0.1778 0.2794)
							(mid 0.249642 0.249642)
							(end 0.2794 0.1778)
						)
						(arc
							(start 0.2794 -0.1778)
							(mid 0.249642 -0.249642)
							(end 0.1778 -0.2794)
						)
					)
					(width 0)
					(fill yes)
				)
			)
		)
		(pad "2" smd custom
			(at 0 0.4445 270)
			(size 0.1397 0.1397)
			(layers "F.Cu" "F.Mask" "F.Paste")
			(net "SAS_EXP_B_PWR1")
			(options
				(clearance outline)
				(anchor circle)
			)
			(primitives
				(gr_poly
					(pts
						(arc
							(start -0.1778 -0.2794)
							(mid -0.249642 -0.249642)
							(end -0.2794 -0.1778)
						)
						(arc
							(start -0.2794 0.1778)
							(mid -0.249642 0.249642)
							(end -0.1778 0.2794)
						)
						(arc
							(start 0.1778 0.2794)
							(mid 0.249642 0.249642)
							(end 0.2794 0.1778)
						)
						(arc
							(start 0.2794 -0.1778)
							(mid 0.249642 -0.249642)
							(end 0.1778 -0.2794)
						)
					)
					(width 0)
					(fill yes)
				)
			)
		)
	)
	(footprint ""
		(layer "F.Cu")
		(at 21.971 -280.543 -90)
		(property "Reference" "C213"
			(at 0 0 270)
			(layer "F.SilkS")
			(hide yes)
			(effects
				(font
					(size 1.27 1.27)
				)
			)
		)
		(property "Value" "SCD1U10V2KX-5GP"
			(at 1.1811 -2.7051 270)
			(unlocked yes)
			(layer "F.Fab")
			(hide yes)
			(effects
				(font
					(size 1.016 1.016)
					(thickness 0.1524)
				)
			)
		)
		(property "Device Type" "C402H22"
			(at 1.1811 -4.2291 270)
			(unlocked yes)
			(layer "F.Fab")
			(hide yes)
			(effects
				(font
					(size 1.016 1.016)
					(thickness 0.1524)
				)
			)
		)
		(duplicate_pad_numbers_are_jumpers no)
		(fp_rect
			(start -0.4318 0.9525)
			(end 0.4318 -0.9525)
			(stroke
				(width 0)
				(type default)
			)
			(fill no)
			(layer "F.CrtYd")
		)
		(fp_rect
			(start -0.4318 0.9525)
			(end 0.4318 -0.9525)
			(stroke
				(width 0)
				(type default)
			)
			(fill no)
			(layer "F.Fab")
		)
		(pad "1" smd custom
			(at 0 -0.4445 270)
			(size 0.1524 0.1524)
			(layers "F.Cu" "F.Mask" "F.Paste")
			(net "P3V3")
			(options
				(clearance outline)
				(anchor circle)
			)
			(primitives
				(gr_poly
					(pts
						(arc
							(start 0.3048 -0.2032)
							(mid 0.275042 -0.275042)
							(end 0.2032 -0.3048)
						)
						(arc
							(start -0.2032 -0.3048)
							(mid -0.275042 -0.275042)
							(end -0.3048 -0.2032)
						)
						(arc
							(start -0.3048 0.2032)
							(mid -0.275042 0.275042)
							(end -0.2032 0.3048)
						)
						(arc
							(start 0.2032 0.3048)
							(mid 0.275042 0.275042)
							(end 0.3048 0.2032)
						)
					)
					(width 0)
					(fill yes)
				)
			)
		)
		(pad "2" smd custom
			(at 0 0.4445 270)
			(size 0.1524 0.1524)
			(layers "F.Cu" "F.Mask" "F.Paste")
			(net "GND")
			(options
				(clearance outline)
				(anchor circle)
			)
			(primitives
				(gr_poly
					(pts
						(arc
							(start 0.3048 -0.2032)
							(mid 0.275042 -0.275042)
							(end 0.2032 -0.3048)
						)
						(arc
							(start -0.2032 -0.3048)
							(mid -0.275042 -0.275042)
							(end -0.3048 -0.2032)
						)
						(arc
							(start -0.3048 0.2032)
							(mid -0.275042 0.275042)
							(end -0.2032 0.3048)
						)
						(arc
							(start 0.2032 0.3048)
							(mid 0.275042 0.275042)
							(end 0.3048 0.2032)
						)
					)
					(width 0)
					(fill yes)
				)
			)
		)
	)
	(footprint ""
		(layer "F.Cu")
		(at 5.079746 -495.8207 -90)
		(property "Reference" "PR45"
			(at 0 0 270)
			(layer "F.SilkS")
			(hide yes)
			(effects
				(font
					(size 1.27 1.27)
				)
			)
		)
		(property "Value" "73K2R2F-GP"
			(at 0.064008 -3.993896 270)
			(unlocked yes)
			(layer "F.Fab")
			(hide yes)
			(effects
				(font
					(size 1.016 1.016)
					(thickness 0.1524)
				)
			)
		)
		(property "Device Type" "R402H16"
			(at 0.064008 -5.517896 270)
			(unlocked yes)
			(layer "F.Fab")
			(hide yes)
			(effects
				(font
					(size 1.016 1.016)
					(thickness 0.1524)
				)
			)
		)
		(duplicate_pad_numbers_are_jumpers no)
		(fp_line
			(start -0.508 -0.9398)
			(end -0.508 0.9398)
			(stroke
				(width 0.1524)
				(type default)
			)
			(layer "F.SilkS")
		)
		(fp_line
			(start 0.508 -0.9398)
			(end -0.508 -0.9398)
			(stroke
				(width 0.1524)
				(type default)
			)
			(layer "F.SilkS")
		)
		(fp_rect
			(start -0.508 0.9398)
			(end 0.508 -0.9398)
			(stroke
				(width 0)
				(type default)
			)
			(fill no)
			(layer "F.CrtYd")
		)
		(fp_rect
			(start -0.508 0.9398)
			(end 0.508 -0.9398)
			(stroke
				(width 0)
				(type default)
			)
			(fill no)
			(layer "F.Fab")
		)
		(pad "1" smd custom
			(at 0 -0.4445 270)
			(size 0.1397 0.1397)
			(layers "F.Cu" "F.Mask" "F.Paste")
			(net "P5VC_VFB")
			(options
				(clearance outline)
				(anchor circle)
			)
			(primitives
				(gr_poly
					(pts
						(arc
							(start -0.1778 -0.2794)
							(mid -0.249642 -0.249642)
							(end -0.2794 -0.1778)
						)
						(arc
							(start -0.2794 0.1778)
							(mid -0.249642 0.249642)
							(end -0.1778 0.2794)
						)
						(arc
							(start 0.1778 0.2794)
							(mid 0.249642 0.249642)
							(end 0.2794 0.1778)
						)
						(arc
							(start 0.2794 -0.1778)
							(mid 0.249642 -0.249642)
							(end 0.1778 -0.2794)
						)
					)
					(width 0)
					(fill yes)
				)
			)
		)
		(pad "2" smd custom
			(at 0 0.4445 270)
			(size 0.1397 0.1397)
			(layers "F.Cu" "F.Mask" "F.Paste")
			(net "P5VC_VFB_NET")
			(options
				(clearance outline)
				(anchor circle)
			)
			(primitives
				(gr_poly
					(pts
						(arc
							(start -0.1778 -0.2794)
							(mid -0.249642 -0.249642)
							(end -0.2794 -0.1778)
						)
						(arc
							(start -0.2794 0.1778)
							(mid -0.249642 0.249642)
							(end -0.1778 0.2794)
						)
						(arc
							(start 0.1778 0.2794)
							(mid 0.249642 0.249642)
							(end 0.2794 0.1778)
						)
						(arc
							(start 0.2794 -0.1778)
							(mid 0.249642 -0.249642)
							(end 0.1778 -0.2794)
						)
					)
					(width 0)
					(fill yes)
				)
			)
		)
	)
)
